(kicad_pcb
	(version 20260206)
	(generator "pcbnew")
	(generator_version "10.0")
	(general
		(thickness 1.6)
		(legacy_teardrops no)
	)
	(paper "A4")
	(title_block
		(title "baseboard — 13948-1b.1110WZS1818.brd")
		(comment 1 "Honey Badger (Wiwynn) / footprints 1479-1487 of 2523")
	)
	(layers
		(0 "F.Cu" signal "TOP")
		(4 "In1.Cu" signal "L2GND")
		(6 "In2.Cu" signal "L3")
		(8 "In3.Cu" signal "L4VCC")
		(10 "In4.Cu" signal "L5VCC")
		(12 "In5.Cu" signal "L6")
		(14 "In6.Cu" signal "L7GND")
		(2 "B.Cu" signal "BOTTOM")
		(9 "F.Adhes" user "F.Adhesive")
		(11 "B.Adhes" user "B.Adhesive")
		(13 "F.Paste" user "Package Geometry/Pastemask Top")
		(15 "B.Paste" user "Package Geometry/Pastemask Bottom")
		(5 "F.SilkS" user "Ref Des/Silkscreen Top")
		(7 "B.SilkS" user "Ref Des/Silkscreen Bottom")
		(1 "F.Mask" user "Board Geometry/Soldermask Top")
		(3 "B.Mask" user "Board Geometry/Soldermask Bottom")
		(17 "Dwgs.User" user "User.Drawings")
		(19 "Cmts.User" user "User.Comments")
		(21 "Eco1.User" user "User.Eco1")
		(23 "Eco2.User" user "User.Eco2")
		(25 "Edge.Cuts" user "Board Geometry/Outline")
		(27 "Margin" user)
		(31 "F.CrtYd" user "Package Geometry/Place Bound Top")
		(29 "B.CrtYd" user "Package Geometry/Place Bound Bottom")
		(35 "F.Fab" user "Ref Des/Assembly Top")
		(33 "B.Fab" user "Ref Des/Assembly Bottom")
	)
	(footprint ""
		(layer "F.Cu")
		(at 289.687 -70.739 90)
		(property "Reference" "PR6889"
			(at 0 0 90)
			(layer "F.SilkS")
			(hide yes)
			(effects
				(font
					(size 1.27 1.27)
				)
			)
		)
		(property "Value" "2K05R2F-GP"
			(at 0.064008 -3.993896 90)
			(unlocked yes)
			(layer "F.Fab")
			(hide yes)
			(effects
				(font
					(size 1.016 1.016)
					(thickness 0.1524)
				)
			)
		)
		(property "Device Type" "R402H16"
			(at 0.064008 -5.517896 90)
			(unlocked yes)
			(layer "F.Fab")
			(hide yes)
			(effects
				(font
					(size 1.016 1.016)
					(thickness 0.1524)
				)
			)
		)
		(duplicate_pad_numbers_are_jumpers no)
		(fp_line
			(start 0.508 -0.9398)
			(end -0.508 -0.9398)
			(stroke
				(width 0.1524)
				(type default)
			)
			(layer "F.SilkS")
		)
		(fp_line
			(start -0.508 -0.9398)
			(end -0.508 0.9398)
			(stroke
				(width 0.1524)
				(type default)
			)
			(layer "F.SilkS")
		)
		(fp_rect
			(start -0.508 0.9398)
			(end 0.508 -0.9398)
			(stroke
				(width 0)
				(type default)
			)
			(fill no)
			(layer "F.CrtYd")
		)
		(fp_rect
			(start -0.508 0.9398)
			(end 0.508 -0.9398)
			(stroke
				(width 0)
				(type default)
			)
			(fill no)
			(layer "F.Fab")
		)
		(pad "1" smd custom
			(at 0 -0.4445 90)
			(size 0.1397 0.1397)
			(layers "F.Cu" "F.Mask" "F.Paste")
			(net "HS_ADR")
			(options
				(clearance outline)
				(anchor circle)
			)
			(primitives
				(gr_poly
					(pts
						(arc
							(start -0.1778 -0.2794)
							(mid -0.249642 -0.249642)
							(end -0.2794 -0.1778)
						)
						(arc
							(start -0.2794 0.1778)
							(mid -0.249642 0.249642)
							(end -0.1778 0.2794)
						)
						(arc
							(start 0.1778 0.2794)
							(mid 0.249642 0.249642)
							(end 0.2794 0.1778)
						)
						(arc
							(start 0.2794 -0.1778)
							(mid 0.249642 -0.249642)
							(end 0.1778 -0.2794)
						)
					)
					(width 0)
					(fill yes)
				)
			)
		)
		(pad "2" smd custom
			(at 0 0.4445 90)
			(size 0.1397 0.1397)
			(layers "F.Cu" "F.Mask" "F.Paste")
			(net "GND")
			(options
				(clearance outline)
				(anchor circle)
			)
			(primitives
				(gr_poly
					(pts
						(arc
							(start -0.1778 -0.2794)
							(mid -0.249642 -0.249642)
							(end -0.2794 -0.1778)
						)
						(arc
							(start -0.2794 0.1778)
							(mid -0.249642 0.249642)
							(end -0.1778 0.2794)
						)
						(arc
							(start 0.1778 0.2794)
							(mid 0.249642 0.249642)
							(end 0.2794 0.1778)
						)
						(arc
							(start 0.2794 -0.1778)
							(mid 0.249642 -0.249642)
							(end 0.1778 -0.2794)
						)
					)
					(width 0)
					(fill yes)
				)
			)
		)
	)
	(footprint ""
		(layer "F.Cu")
		(at 68.834 -47.879 -90)
		(property "Reference" "SC935"
			(at 0 0 270)
			(layer "F.SilkS")
			(hide yes)
			(effects
				(font
					(size 1.27 1.27)
				)
			)
		)
		(property "Value" "SC22U6D3V5MX-2GP"
			(at -0.0762 -6.1214 270)
			(unlocked yes)
			(layer "F.Fab")
			(hide yes)
			(effects
				(font
					(size 1.016 1.016)
					(thickness 0.1524)
				)
			)
		)
		(property "Device Type" "C805H58"
			(at -0.0762 -8.1534 270)
			(unlocked yes)
			(layer "F.Fab")
			(hide yes)
			(effects
				(font
					(size 1.016 1.016)
					(thickness 0.1524)
				)
			)
		)
		(duplicate_pad_numbers_are_jumpers no)
		(fp_line
			(start 0.635 0)
			(end -0.635 0)
			(stroke
				(width 0.508)
				(type default)
			)
			(layer "F.SilkS")
		)
		(fp_rect
			(start -0.9652 1.778)
			(end 0.9652 -1.778)
			(stroke
				(width 0)
				(type default)
			)
			(fill no)
			(layer "F.CrtYd")
		)
		(fp_poly
			(pts
				(xy -0.9652 -1.778) (xy 0.9652 -1.778) (xy 0.9652 1.778) (xy -0.9652 1.778)
			)
			(stroke
				(width 0)
				(type default)
			)
			(fill no)
			(layer "F.Fab")
		)
		(pad "1" smd rect
			(at 0 -0.9652 270)
			(size 1.397 1.143)
			(layers "F.Cu" "F.Mask" "F.Paste")
			(net "SAS0_VDDH")
		)
		(pad "2" smd rect
			(at 0 0.9652 270)
			(size 1.397 1.143)
			(layers "F.Cu" "F.Mask" "F.Paste")
			(net "GND")
		)
	)
	(footprint ""
		(layer "F.Cu")
		(at 330.708 -118.491)
		(property "Reference" "PL2"
			(at 0 0 0)
			(layer "F.SilkS")
			(hide yes)
			(effects
				(font
					(size 1.27 1.27)
				)
			)
		)
		(property "Value" "BLM21PG220SN1DGP"
			(at 0.0254 -5.6896 0)
			(unlocked yes)
			(layer "F.Fab")
			(hide yes)
			(effects
				(font
					(size 1.016 1.016)
					(thickness 0.1524)
				)
			)
		)
		(property "Device Type" "L20125H42"
			(at 0.0254 -7.5946 0)
			(unlocked yes)
			(layer "F.Fab")
			(hide yes)
			(effects
				(font
					(size 1.016 1.016)
					(thickness 0.1524)
				)
			)
		)
		(duplicate_pad_numbers_are_jumpers no)
		(fp_line
			(start -0.9144 -1.7018)
			(end -0.9144 1.7018)
			(stroke
				(width 0.1524)
				(type default)
			)
			(layer "F.SilkS")
		)
		(fp_line
			(start -0.9144 1.7018)
			(end 0.9144 1.7018)
			(stroke
				(width 0.1524)
				(type default)
			)
			(layer "F.SilkS")
		)
		(fp_line
			(start 0.9144 -1.7018)
			(end -0.9144 -1.7018)
			(stroke
				(width 0.1524)
				(type default)
			)
			(layer "F.SilkS")
		)
		(fp_line
			(start 0.9144 1.7018)
			(end 0.9144 -1.7018)
			(stroke
				(width 0.1524)
				(type default)
			)
			(layer "F.SilkS")
		)
		(fp_rect
			(start -1.0033 1.778)
			(end 1.0033 -1.778)
			(stroke
				(width 0)
				(type default)
			)
			(fill no)
			(layer "F.CrtYd")
		)
		(fp_poly
			(pts
				(xy -1.0033 -1.778) (xy 1.0033 -1.778) (xy 1.0033 1.778) (xy -1.0033 1.778)
			)
			(stroke
				(width 0)
				(type default)
			)
			(fill no)
			(layer "F.Fab")
		)
		(pad "1" smd rect
			(at 0 -0.9652)
			(size 1.397 1.143)
			(layers "F.Cu" "F.Mask" "F.Paste")
			(net "P12V")
		)
		(pad "2" smd rect
			(at 0 0.9652)
			(size 1.397 1.143)
			(layers "F.Cu" "F.Mask" "F.Paste")
			(net "P3V3_STBY_VIN")
		)
	)
	(footprint ""
		(layer "F.Cu")
		(at 105.7148 -62.3062)
		(property "Reference" "STP59"
			(at 0 0 0)
			(layer "F.SilkS")
			(hide yes)
			(effects
				(font
					(size 1.27 1.27)
				)
			)
		)
		(property "Value" "TPAD28"
			(at 0.0127 -1.8034 0)
			(unlocked yes)
			(layer "F.Fab")
			(hide yes)
			(effects
				(font
					(size 1.016 1.016)
					(thickness 0.1524)
				)
			)
		)
		(property "Device Type" "TPAD28"
			(at 0.0127 -3.3274 0)
			(unlocked yes)
			(layer "F.Fab")
			(hide yes)
			(effects
				(font
					(size 1.016 1.016)
					(thickness 0.1524)
				)
			)
		)
		(duplicate_pad_numbers_are_jumpers no)
		(fp_poly
			(pts
				(arc
					(start 0.3556 0)
					(mid -0.3556 0)
					(end 0.3556 0)
				)
			)
			(stroke
				(width 0)
				(type default)
			)
			(fill no)
			(layer "F.CrtYd")
		)
		(fp_poly
			(pts
				(arc
					(start 0.6096 0)
					(mid -0.6096 0)
					(end 0.6096 0)
				)
			)
			(stroke
				(width 0)
				(type default)
			)
			(fill no)
			(layer "F.Fab")
		)
		(pad "1" smd circle
			(at 0 0)
			(size 0.7112 0.7112)
			(layers "F.Cu" "F.Mask" "F.Paste")
			(net "IOC_TRST_N")
		)
	)
	(footprint ""
		(layer "F.Cu")
		(at 274.193 -166.624 90)
		(property "Reference" "R539"
			(at 0 0 90)
			(layer "F.SilkS")
			(hide yes)
			(effects
				(font
					(size 1.27 1.27)
				)
			)
		)
		(property "Value" "0R2J-2-GP"
			(at 0.064008 -3.993896 90)
			(unlocked yes)
			(layer "F.Fab")
			(hide yes)
			(effects
				(font
					(size 1.016 1.016)
					(thickness 0.1524)
				)
			)
		)
		(property "Device Type" "R402H16"
			(at 0.064008 -5.517896 90)
			(unlocked yes)
			(layer "F.Fab")
			(hide yes)
			(effects
				(font
					(size 1.016 1.016)
					(thickness 0.1524)
				)
			)
		)
		(duplicate_pad_numbers_are_jumpers no)
		(fp_line
			(start 0.508 -0.9398)
			(end -0.508 -0.9398)
			(stroke
				(width 0.1524)
				(type default)
			)
			(layer "F.SilkS")
		)
		(fp_line
			(start -0.508 -0.9398)
			(end -0.508 0.9398)
			(stroke
				(width 0.1524)
				(type default)
			)
			(layer "F.SilkS")
		)
		(fp_rect
			(start -0.508 0.9398)
			(end 0.508 -0.9398)
			(stroke
				(width 0)
				(type default)
			)
			(fill no)
			(layer "F.CrtYd")
		)
		(fp_rect
			(start -0.508 0.9398)
			(end 0.508 -0.9398)
			(stroke
				(width 0)
				(type default)
			)
			(fill no)
			(layer "F.Fab")
		)
		(pad "1" smd custom
			(at 0 -0.4445 90)
			(size 0.1397 0.1397)
			(layers "F.Cu" "F.Mask" "F.Paste")
			(net "PG_STAT_P0V955_C")
			(options
				(clearance outline)
				(anchor circle)
			)
			(primitives
				(gr_poly
					(pts
						(arc
							(start -0.1778 -0.2794)
							(mid -0.249642 -0.249642)
							(end -0.2794 -0.1778)
						)
						(arc
							(start -0.2794 0.1778)
							(mid -0.249642 0.249642)
							(end -0.1778 0.2794)
						)
						(arc
							(start 0.1778 0.2794)
							(mid 0.249642 0.249642)
							(end 0.2794 0.1778)
						)
						(arc
							(start 0.2794 -0.1778)
							(mid 0.249642 -0.249642)
							(end 0.1778 -0.2794)
						)
					)
					(width 0)
					(fill yes)
				)
			)
		)
		(pad "2" smd custom
			(at 0 0.4445 90)
			(size 0.1397 0.1397)
			(layers "F.Cu" "F.Mask" "F.Paste")
			(net "PWGD_P0V955_C_PG_R")
			(options
				(clearance outline)
				(anchor circle)
			)
			(primitives
				(gr_poly
					(pts
						(arc
							(start -0.1778 -0.2794)
							(mid -0.249642 -0.249642)
							(end -0.2794 -0.1778)
						)
						(arc
							(start -0.2794 0.1778)
							(mid -0.249642 0.249642)
							(end -0.1778 0.2794)
						)
						(arc
							(start 0.1778 0.2794)
							(mid 0.249642 0.249642)
							(end 0.2794 0.1778)
						)
						(arc
							(start 0.2794 -0.1778)
							(mid 0.249642 -0.249642)
							(end 0.1778 -0.2794)
						)
					)
					(width 0)
					(fill yes)
				)
			)
		)
	)
	(footprint ""
		(layer "F.Cu")
		(at 201.549 -185.547)
		(property "Reference" "C304"
			(at 0 0 0)
			(layer "F.SilkS")
			(hide yes)
			(effects
				(font
					(size 1.27 1.27)
				)
			)
		)
		(property "Value" "SC1U10V3KX-4GP-U"
			(at 0 -2.8194 0)
			(unlocked yes)
			(layer "F.Fab")
			(hide yes)
			(effects
				(font
					(size 1.016 1.016)
					(thickness 0.1524)
				)
			)
		)
		(property "Device Type" "C603H36"
			(at 0 -4.3434 0)
			(unlocked yes)
			(layer "F.Fab")
			(hide yes)
			(effects
				(font
					(size 1.016 1.016)
					(thickness 0.1524)
				)
			)
		)
		(duplicate_pad_numbers_are_jumpers no)
		(fp_line
			(start 0.508 0)
			(end -0.508 0)
			(stroke
				(width 0.2032)
				(type default)
			)
			(layer "F.SilkS")
		)
		(fp_rect
			(start -0.5842 1.3335)
			(end 0.5842 -1.3335)
			(stroke
				(width 0)
				(type default)
			)
			(fill no)
			(layer "F.CrtYd")
		)
		(fp_rect
			(start -0.5842 1.3335)
			(end 0.5842 -1.3335)
			(stroke
				(width 0)
				(type default)
			)
			(fill no)
			(layer "F.Fab")
		)
		(pad "1" smd custom
			(at 0 -0.762)
			(size 0.2159 0.2159)
			(layers "F.Cu" "F.Mask" "F.Paste")
			(net "HB_A_IN")
			(options
				(clearance outline)
				(anchor circle)
			)
			(primitives
				(gr_poly
					(pts
						(arc
							(start -0.3302 -0.4318)
							(mid -0.402042 -0.402042)
							(end -0.4318 -0.3302)
						)
						(arc
							(start -0.4318 0.3302)
							(mid -0.402042 0.402042)
							(end -0.3302 0.4318)
						)
						(arc
							(start 0.3302 0.4318)
							(mid 0.402042 0.402042)
							(end 0.4318 0.3302)
						)
						(arc
							(start 0.4318 -0.3302)
							(mid 0.402042 -0.402042)
							(end 0.3302 -0.4318)
						)
					)
					(width 0)
					(fill yes)
				)
			)
		)
		(pad "2" smd custom
			(at 0 0.762)
			(size 0.2159 0.2159)
			(layers "F.Cu" "F.Mask" "F.Paste")
			(net "GND")
			(options
				(clearance outline)
				(anchor circle)
			)
			(primitives
				(gr_poly
					(pts
						(arc
							(start -0.3302 -0.4318)
							(mid -0.402042 -0.402042)
							(end -0.4318 -0.3302)
						)
						(arc
							(start -0.4318 0.3302)
							(mid -0.402042 0.402042)
							(end -0.3302 0.4318)
						)
						(arc
							(start 0.3302 0.4318)
							(mid 0.402042 0.402042)
							(end 0.4318 0.3302)
						)
						(arc
							(start 0.4318 -0.3302)
							(mid 0.402042 -0.402042)
							(end 0.3302 -0.4318)
						)
					)
					(width 0)
					(fill yes)
				)
			)
		)
	)
	(footprint ""
		(layer "F.Cu")
		(at 339.716872 -171.395136 180)
		(property "Reference" "R277"
			(at 0 0 180)
			(layer "F.SilkS")
			(hide yes)
			(effects
				(font
					(size 1.27 1.27)
				)
			)
		)
		(property "Value" "0R2J-2-GP"
			(at 0.064008 -3.993896 180)
			(unlocked yes)
			(layer "F.Fab")
			(hide yes)
			(effects
				(font
					(size 1.016 1.016)
					(thickness 0.1524)
				)
			)
		)
		(property "Device Type" "R402H16"
			(at 0.064008 -5.517896 180)
			(unlocked yes)
			(layer "F.Fab")
			(hide yes)
			(effects
				(font
					(size 1.016 1.016)
					(thickness 0.1524)
				)
			)
		)
		(duplicate_pad_numbers_are_jumpers no)
		(fp_line
			(start 0.508 -0.9398)
			(end -0.508 -0.9398)
			(stroke
				(width 0.1524)
				(type default)
			)
			(layer "F.SilkS")
		)
		(fp_line
			(start -0.508 -0.9398)
			(end -0.508 0.9398)
			(stroke
				(width 0.1524)
				(type default)
			)
			(layer "F.SilkS")
		)
		(fp_rect
			(start -0.508 0.9398)
			(end 0.508 -0.9398)
			(stroke
				(width 0)
				(type default)
			)
			(fill no)
			(layer "F.CrtYd")
		)
		(fp_rect
			(start -0.508 0.9398)
			(end 0.508 -0.9398)
			(stroke
				(width 0)
				(type default)
			)
			(fill no)
			(layer "F.Fab")
		)
		(pad "1" smd custom
			(at 0 -0.4445 180)
			(size 0.1397 0.1397)
			(layers "F.Cu" "F.Mask" "F.Paste")
			(net "BMC_UART_SWITCH_R")
			(options
				(clearance outline)
				(anchor circle)
			)
			(primitives
				(gr_poly
					(pts
						(arc
							(start -0.1778 -0.2794)
							(mid -0.249642 -0.249642)
							(end -0.2794 -0.1778)
						)
						(arc
							(start -0.2794 0.1778)
							(mid -0.249642 0.249642)
							(end -0.1778 0.2794)
						)
						(arc
							(start 0.1778 0.2794)
							(mid 0.249642 0.249642)
							(end 0.2794 0.1778)
						)
						(arc
							(start 0.2794 -0.1778)
							(mid 0.249642 -0.249642)
							(end 0.1778 -0.2794)
						)
					)
					(width 0)
					(fill yes)
				)
			)
		)
		(pad "2" smd custom
			(at 0 0.4445 180)
			(size 0.1397 0.1397)
			(layers "F.Cu" "F.Mask" "F.Paste")
			(net "BMC_UART_SWITCH_2")
			(options
				(clearance outline)
				(anchor circle)
			)
			(primitives
				(gr_poly
					(pts
						(arc
							(start -0.1778 -0.2794)
							(mid -0.249642 -0.249642)
							(end -0.2794 -0.1778)
						)
						(arc
							(start -0.2794 0.1778)
							(mid -0.249642 0.249642)
							(end -0.1778 0.2794)
						)
						(arc
							(start 0.1778 0.2794)
							(mid 0.249642 0.249642)
							(end 0.2794 0.1778)
						)
						(arc
							(start 0.2794 -0.1778)
							(mid 0.249642 -0.249642)
							(end 0.1778 -0.2794)
						)
					)
					(width 0)
					(fill yes)
				)
			)
		)
	)
	(footprint ""
		(layer "F.Cu")
		(at 119.64797 -76.581 -90)
		(property "Reference" "SC1125"
			(at 0 0 270)
			(layer "F.SilkS")
			(hide yes)
			(effects
				(font
					(size 1.27 1.27)
				)
			)
		)
		(property "Value" "SC12P50V2JN-3GP"
			(at 1.1811 -2.7051 270)
			(unlocked yes)
			(layer "F.Fab")
			(hide yes)
			(effects
				(font
					(size 1.016 1.016)
					(thickness 0.1524)
				)
			)
		)
		(property "Device Type" "C402H24"
			(at 1.1811 -4.2291 270)
			(unlocked yes)
			(layer "F.Fab")
			(hide yes)
			(effects
				(font
					(size 1.016 1.016)
					(thickness 0.1524)
				)
			)
		)
		(duplicate_pad_numbers_are_jumpers no)
		(fp_rect
			(start -0.4318 0.9525)
			(end 0.4318 -0.9525)
			(stroke
				(width 0)
				(type default)
			)
			(fill no)
			(layer "F.CrtYd")
		)
		(fp_rect
			(start -0.4318 0.9525)
			(end 0.4318 -0.9525)
			(stroke
				(width 0)
				(type default)
			)
			(fill no)
			(layer "F.Fab")
		)
		(pad "1" smd custom
			(at 0 -0.4445 270)
			(size 0.1524 0.1524)
			(layers "F.Cu" "F.Mask" "F.Paste")
			(net "EXP_REF_CLK_N_R")
			(options
				(clearance outline)
				(anchor circle)
			)
			(primitives
				(gr_poly
					(pts
						(arc
							(start 0.3048 -0.2032)
							(mid 0.275042 -0.275042)
							(end 0.2032 -0.3048)
						)
						(arc
							(start -0.2032 -0.3048)
							(mid -0.275042 -0.275042)
							(end -0.3048 -0.2032)
						)
						(arc
							(start -0.3048 0.2032)
							(mid -0.275042 0.275042)
							(end -0.2032 0.3048)
						)
						(arc
							(start 0.2032 0.3048)
							(mid 0.275042 0.275042)
							(end 0.3048 0.2032)
						)
					)
					(width 0)
					(fill yes)
				)
			)
		)
		(pad "2" smd custom
			(at 0 0.4445 270)
			(size 0.1524 0.1524)
			(layers "F.Cu" "F.Mask" "F.Paste")
			(net "GND")
			(options
				(clearance outline)
				(anchor circle)
			)
			(primitives
				(gr_poly
					(pts
						(arc
							(start 0.3048 -0.2032)
							(mid 0.275042 -0.275042)
							(end 0.2032 -0.3048)
						)
						(arc
							(start -0.2032 -0.3048)
							(mid -0.275042 -0.275042)
							(end -0.3048 -0.2032)
						)
						(arc
							(start -0.3048 0.2032)
							(mid -0.275042 0.275042)
							(end -0.2032 0.3048)
						)
						(arc
							(start 0.2032 0.3048)
							(mid 0.275042 0.275042)
							(end 0.3048 0.2032)
						)
					)
					(width 0)
					(fill yes)
				)
			)
		)
	)
	(footprint ""
		(layer "F.Cu")
		(at 44.638722 -136.498584 -90)
		(property "Reference" "SC1122"
			(at 0 0 270)
			(layer "F.SilkS")
			(hide yes)
			(effects
				(font
					(size 1.27 1.27)
				)
			)
		)
		(property "Value" "SCD1U16V2KX-3GP"
			(at 1.1811 -2.7051 270)
			(unlocked yes)
			(layer "F.Fab")
			(hide yes)
			(effects
				(font
					(size 1.016 1.016)
					(thickness 0.1524)
				)
			)
		)
		(property "Device Type" "C402H22"
			(at 1.1811 -4.2291 270)
			(unlocked yes)
			(layer "F.Fab")
			(hide yes)
			(effects
				(font
					(size 1.016 1.016)
					(thickness 0.1524)
				)
			)
		)
		(duplicate_pad_numbers_are_jumpers no)
		(fp_rect
			(start -0.4318 0.9525)
			(end 0.4318 -0.9525)
			(stroke
				(width 0)
				(type default)
			)
			(fill no)
			(layer "F.CrtYd")
		)
		(fp_rect
			(start -0.4318 0.9525)
			(end 0.4318 -0.9525)
			(stroke
				(width 0)
				(type default)
			)
			(fill no)
			(layer "F.Fab")
		)
		(pad "1" smd custom
			(at 0 -0.4445 270)
			(size 0.1524 0.1524)
			(layers "F.Cu" "F.Mask" "F.Paste")
			(net "P1V8_STBY")
			(options
				(clearance outline)
				(anchor circle)
			)
			(primitives
				(gr_poly
					(pts
						(arc
							(start 0.3048 -0.2032)
							(mid 0.275042 -0.275042)
							(end 0.2032 -0.3048)
						)
						(arc
							(start -0.2032 -0.3048)
							(mid -0.275042 -0.275042)
							(end -0.3048 -0.2032)
						)
						(arc
							(start -0.3048 0.2032)
							(mid -0.275042 0.275042)
							(end -0.2032 0.3048)
						)
						(arc
							(start 0.2032 0.3048)
							(mid 0.275042 0.275042)
							(end 0.3048 0.2032)
						)
					)
					(width 0)
					(fill yes)
				)
			)
		)
		(pad "2" smd custom
			(at 0 0.4445 270)
			(size 0.1524 0.1524)
			(layers "F.Cu" "F.Mask" "F.Paste")
			(net "GND")
			(options
				(clearance outline)
				(anchor circle)
			)
			(primitives
				(gr_poly
					(pts
						(arc
							(start 0.3048 -0.2032)
							(mid 0.275042 -0.275042)
							(end 0.2032 -0.3048)
						)
						(arc
							(start -0.2032 -0.3048)
							(mid -0.275042 -0.275042)
							(end -0.3048 -0.2032)
						)
						(arc
							(start -0.3048 0.2032)
							(mid -0.275042 0.275042)
							(end -0.2032 0.3048)
						)
						(arc
							(start 0.2032 0.3048)
							(mid 0.275042 0.275042)
							(end 0.3048 0.2032)
						)
					)
					(width 0)
					(fill yes)
				)
			)
		)
	)
)
